# Primary and Alternate BOM of B91.01110.0009_SCC w IOC.xls — Sheet0 (bom)
| Part Number | B91.01110.0009 |  |  |  |  |  |  |  |  |  |  |  |  |
| Revision | E |  |  |  |  |  |  |  |  |  |  |  |  |
| Sequence | 1 |  |  |  |  |  |  |  |  |  |  |  |  |
| Description | BRYCECANYON 19-000769-4 SCC W/IOC SP P M |  |  |  |  |  |  |  |  |  |  |  |  |
| Project Code | BPD011010001 |  |  |  |  |  |  |  |  |  |  |  |  |
| Latest Revision? | YES |  |  |  |  |  |  |  |  |  |  |  |  |
| PDM BOM List |  |  |  |  |  |  |  |  |  |  |  |  |  |
| Level | Parent Number | Part Number | Description | Green Factor | Manufacturer | Manufacturer Part Number | Source | BOM Usage | M/P Code | S/D | Qty | UoM | Location |
| 1 | B91.01110.0009 | B55.01102.0003 | BRYCE CANYON SCC W/IOC GCE-1 P MAIN(D) | R2; |  |  |  | M | Manufacture |  | 1 | PCS |  |
| 2 | B55.01102.0003 | 020.80777.0001 | CONN PWR XCEDE JX310-50387_REVB | R2_SA;HF_SA; | AMPHENOL | JX310-50387 | Single |  | Purchase | DIP | 1 | PCS | CN1 |
| 2 | B55.01102.0003 | 020.80815.0011 | CONN SIGNAL XCEDE JX310-50417_REVB | R2_SA; | AMPHENOL | JX310-50417_RevB | Single |  | Purchase | DIP | 1 | PCS | CN6 |
| 2 | B55.01102.0003 | 020.80963.0001 | CONN SIGNAL XCEDE JX310-50375_REVC | R2_SA; | AMPHENOL | JX310-50375_RevC | Single |  | Purchase | DIP | 1 | PCS | CN2 |
| 2 | B55.01102.0003 | 20.82057.036 | CONN CTR IPASS 36P 76867-1011 PRESSFIT | R2_SA;HF_SA; | MOLEX | 76867-1011 | Multiple |  | Purchase | DIP | 1 | PCS | MSAS1 |
| A(Alternative to previous component) | B55.01102.0003 | 20.82058.036 | CONN CTR RT 36P MINI SAS G40H11332HR-W | R2_SA;HF_SA; | AMPHENOL | G40H11332HR-W |  |  | Purchase |  |  |  |  |
| 2 | B55.01102.0003 | 40.58D03.001 | LBL POLYIMIDE31.8*6.35 BARCODE | R2_SA;HF_SA;G_SA; | LABELJET | 40.58D03.001 | Single |  | Purchase | DIP | 2 | PCS |  |
| 2 | B55.01102.0003 | 40.6E727.001 | LBL 50X15MM BLANK WHITE POLYESTER | R2_SA;HF_SA; | WISTRON | 40.6E727.001 | Single |  | Purchase | DIP | 1 | PCS |  |
| 2 | B55.01102.0003 | 640.00X01.0001 | LBL 7X7MM  FOR SONIC | R2_SA;HF_SA; | WISTRON | 640.00X01.0001 | Single |  | Purchase | DIP | 1 | PCS |  |
| 2 | B55.01102.0003 | B34.0110S.0001 | HSINK 50X40X30_PUSHPIN_PAD SPONGE, CCI | R2_SA;HF_SA; | CCI | B34.0110S.0001 | Single |  | Purchase | DIP | 1 | PCS |  |
| 2 | B55.01102.0003 | B34.0110T.0001 | HSINK 64X50X30_PUSHPIN_PAD SPONGE, CCI | R2_SA;HF_SA; | CCI | B34.0110T.0001 | Single |  | Purchase | DIP | 1 | PCS |  |
| 2 | B55.01102.0003 | B42.0111G.0021 | LATCH SCC R TEXTURE BRYCE CANYON MP | R2_SA;HF_SA; | FIVETECH | B42.0111G.0021 | Single |  | Purchase | DIP | 1 | PCS |  |
| 2 | B55.01102.0003 | B42.0111H.0021 | LATCH SCC L TEXTURE BRYCE CANYON MP | R2_SA;HF_SA; | FIVETECH | B42.0111H.0021 | Single |  | Purchase | DIP | 1 | PCS |  |
| 2 | B55.01102.0003 | B55.01102.M003 | BRYCE CANYON SCC W/IOC GCE-1 P MAIN(S) | R2; |  |  |  | M | Manufacture | DIP | 1 | PCS |  |
| 3 | B55.01102.M003 | 064.41215.06DS | CHIP RES 4.12K F 1/16W 0402 | R2_SA;HF_SA;G_SA; | YAGEO;WALSIN;KOA | RC0402FR-074K12L;WR04X4121FTL;RK73H1ETQTP4121F | Multiple |  | Purchase | SMT | 1 | PCS | R15 |
| 3 | B55.01102.M003 | 064.51015.06DS | CHIP RES 5.1K F 1/16W 0402 | R2_SA;HF_SA;G_SA; | YAGEO;WALSIN;KOA | RC0402FR-075K1L;WR04X5101FTL;RK73H1ETQTP5101F | Multiple |  | Purchase | SMT | 1 | PCS | R16 |
| 3 | B55.01102.M003 | 064.R0035.0701 | CHIP RES 0.003 F 1W 0612 TCR+- 150PPM | R2_SA;HF_SA; | CYNTEC;VISHAY | RL1632L4-R003-FNH;WSK06123L000FEA | Multiple |  | Purchase | SMT | 1 | PCS | R14 |
| 3 | B55.01102.M003 | 068.1812N.1021 | CHIP IND 180NH K FP1007R6-R18-R | R2_SA;HF_SA; | COOPER | FP1007R6-R18-R | Multiple |  | Purchase | SMT | 1 | PCS | L31 |
| A | B55.01102.M003 | 068.1812N.1081 | CHIP IND 180NH K HCB1070C-181 | R2_SA;HF_SA; | DELTA | HCB1070C-181 |  |  | Purchase |  |  |  |  |
| 3 | B55.01102.M003 | 071.09306.0A0I | IC SMBUS/I2C PCA9306DCTR SSOP8 | R2_SA;HF_SA; | TI | PCA9306DCTR | Multiple |  | Purchase | SMT | 8 | PCS | U35 U36 U37 U38 U39 U40 U41 U46 |
| A | B55.01102.M003 | 71.09306.00W | IC SMBUS/I2C PCA9306DP1 TSSOP 8P | R2_SA;HF_SA; | NXP | PCA9306DP1,125 |  |  | Purchase |  |  |  |  |
| 3 | B55.01102.M003 | 073.03166.000B | IC ANALOG SWITCH NX3L1G66GW,125 TSSOP5 | R2_SA;HF_SA; | NXP | NX3L1G66GW,125 | Single |  | Purchase | SMT | 2 | PCS | U119 U120 |
| 3 | B55.01102.M003 | 074.01278.0A7Z | IC SWAP CTRL ADM1278-2ACPZ-RL LFCSP 32P | R2_SA;HF_SA; | ADI | ADM1278-2ACPZ-RL | Single |  | Purchase | SMT | 1 | PCS | U5 |
| 3 | B55.01102.M003 | 074.03808.M001 | IC RESET TPS3808G01DBVR SOT-23 6P(LILY) | R2_SA;HF_SA; | TI | TPS3808G01DBVR | Single |  | Purchase | SMT | 2 | PCS | U16 U23 |
| 3 | B55.01102.M003 | 075.87350.0071 | IC FET MOS CSD87350Q5D SON 8P | R2_SA;HF_SA; | TI | CSD87350Q5D | Single |  | Purchase | SMT | 1 | PCS | Q7 |
| 3 | B55.01102.M003 | 077.51571.0001 | CHIP CAP EL POLY 150U 6.3V M7343 ESR17 | R2_SA;HF_SA; | PANASONIC | EEJRX0J151R | Multiple |  | Purchase | SMT | 2 | PCS | TC4 TC5 |
| A | B55.01102.M003 | 077.C1571.0011 | CHIP CAP POLY T 150U 6.3V M7343 ESR18 | R2_SA;HF_SA; | NECTOKIN | PSKV0J157M018C |  |  | Purchase |  |  |  |  |
| A | B55.01102.M003 | 77.C1571.16L | CHIP CAP POLY T 150U 6.3V M7343 | R2_SA;HF_SA; | PANASONIC | EEFSX0J151ER |  |  | Purchase |  |  |  |  |
| 3 | B55.01102.M003 | 078.10321.02S1 | CHIP CAP C 0.01U 16V K0201 X7R | R2_SA;HF_SA;G_SA; | DARFON;MURATA;TAIYO;WALSIN;YAGEO;SAMSUNG | C0603X7R103KET;GRM033R71C103KE14D;EMK063B7103KP-F;0201B103K160CT;CC0201KRX7R7BB103;CL03B103KO3NNNC | Multiple |  | Purchase | SMT | 120 | PCS | C1 C10 C11 C12 C13 C14 C15 C16 C17 C18 C19 C2 C20 C21 C22 C23 C24 C25 C26 C27 C28 C29 C3 C30 C31 C32 C327 C328 C329 C33 C330 C331 C332 C333 C336 C337 C338 C339 C34 C340 C341 C342 C343 C344 C35 C36 C37 C38 C39 C4 C40 C41 C42 C43 C44 C45 C46 C47 C48 C49 C5 C50 C51 C52 C53 C54 C55 C56 C57 C58 C59 C6 C60 C61 C610 C62 C63 C64 C65 C66 C67 C677 C678 C679 C68 C680 C681 C682 C683 C69 C7 C70 C71 C72 C73 C74 C75 C76 C77 C78 C79 C8 C80 C81 C82 C83 C84 C85 C86 C87 C88 C89 C9 C90 C91 C92 C93 C94 C95 C96 |
| 3 | B55.01102.M003 | 078.10521.08F1 | CHIP CAP C 1UF 16V K 0402 X6S | R2_SA;HF_SA;G_SA; | MURATA;DARFON;YAGEO;TAIYO | GRM155C81C105KE11D;C1005X6S105KET;CC0402KRX6S7BB105;LMK105C6105KV-F | Multiple |  | Purchase | SMT | 18 | PCS | C214 C353 C357 C361 C365 C369 C373 C379 C385 C396 C482 C483 C484 C485 C486 C487 C518 C520 |
| 3 | B55.01102.M003 | 078.10621.0211 | CHIP CAP C 10UF 16V K0805 X7R | R2_SA;HF_SA;G_SA; | SAMSUNG;YAGEO | CL21B106KOQNNNE;CC0805KKX7R7BB106 | Multiple |  | Purchase | SMT | 23 | PCS | C527 C564 C565 C595 C635 C636 C637 C643 C644 C645 C657 C666 C667 C668 C669 C670 C671 C698 C699 C700 C701 C702 C709 |
| 3 | B55.01102.M003 | 078.22610.08B1 | CHIP CAP C 22U 6.3V M0603 X6S MP | R2_SA;HF_SA; | MURATA;DARFON;WALSIN;YAGEO | GRM188C80J226ME15D;C1608X6S226MCT;0603S226M6R3CT;CC0603MRX6S5BB226 | Multiple |  | Purchase | SMT | 26 | PCS | C192 C196 C200 C204 C208 C228 C235 C242 C249 C256 C263 C275 C288 C295 C296 C303 C310 C351 C355 C359 C363 C367 C371 C377 C384 C719 |
| 3 | B55.01102.M003 | 078.47522.0211 | CHIP CAP C 4.7U 25V K0805 X7R | R2_SA;HF_SA;G_SA; | DARFON;MURATA;SAMSUNG;TAIYO;WALSIN;YAGEO | C2012X7R475KFP;GRM21BR71E475KA73L;CL21B475KAFNNNE;TMK212AB7475KG-T;0805B475K250CT;CC0805KKX7R8BB475 | Multiple |  | Purchase | SMT | 5 | PCS | C347 C511 C607 C616 C639 |
| 3 | B55.01102.M003 | 082.30005.0311 | XTAL 25MHZ 12P30PPM HSX211S SMD HARMONY | R2_SA;HF_SA; | HARMONY | X2C025000FC1H-HX | Multiple |  | Purchase | SMT | 2 | PCS | X1 X2 |
| A | B55.01102.M003 | 82.30020.I61 | XTAL 25MHZ 20PPM 12PF HCX-1AB SMD | R2_SA;HF_SA; | HOSONIC | E1AB25.0000F12D22 |  |  | Purchase |  |  |  |  |
| 3 | B55.01102.M003 | 084.00925.003N | FET MOS PH0925CL,115 NC LFPAK 4P | R2_SA;HF_SA; | NXP | PH0925CL,115 | Single |  | Purchase | SMT | 1 | PCS | Q23 |
| 3 | B55.01102.M003 | 084.3K324.0031 | FET MOS NC SSM3K324R SOT-23F 3P | R2_SA;HF_SA; | TOSHIBA | SSM3K324R | Multiple |  | Purchase | SMT | 6 | PCS | Q11 Q16 Q2 Q3 Q4 Q9 |
| A | B55.01102.M003 | 084.06244.0031 | FET MOS IRLML6244TRPBF SOT-23 | R2_SA;HF_SA; | IR | IRLML6244TRPBF |  |  | Purchase |  |  |  |  |
| 3 | B55.01102.M003 | 19-000387$AA | IC CTRL SAS3008C0-1-DB-500020657 FPBGA | R2_SA;HF_SA; | LSI | 500020657 | Single |  | Purchase | SMT | 1 | PCS | U2 |
| 3 | B55.01102.M003 | 63.00000.00L | CHIP RES 0 J 1/10W 0603 | R2_SA;HF_SA;G_SA; | TA-I ; RALEC ; YAGEO ; WALSIN | RM06JTN0 ; RTT03000JTP ; RC0603JR-070RL ; WR06X000PTL | Multiple |  | Purchase | SMT | 3 | PCS | R480 R481 R482 |
| 3 | B55.01102.M003 | 63.10034.1DL | CHIP RES 10 J 1/16W 0402 | R2_SA;HF_SA;G_SA; | TA-I ; RALEC ; CYNTEC ; YAGEO;WALSIN | RM04JTN100 ; RTT02100JTH ; RR0510S-100-JN ; RC0402JR-0710RL;WR04X100JTL | Multiple |  | Purchase | SMT | 1 | PCS | R474 |
| 3 | B55.01102.M003 | 63.10234.1DL | CHIP RES 1K J 1/16W 0402 | R2_SA;HF_SA;G_SA; | TA-I;RALEC;CYNTEC;YAGEO;WALSIN | RM04JTN102 ; RTT02102JTH ; RR0510S-102-JN ; RC0402JR-071KL;WR04X102JTL | Multiple |  | Purchase | SMT | 2 | PCS | R531 R607 |
| 3 | B55.01102.M003 | 63.10434.L1L | CHIP RES 100K J 1/16W 0402 13" REEL | R2_SA;HF_SA;G_SA; | YAGEO;RALEC;WALSIN;TAI | RC0402JR-13100KL;RTT02104JH5;WR04X104 JHL;RM04JLN104 | Multiple |  | Purchase | SMT | 3 | PCS | R17 R18 R19 |
| 3 | B55.01102.M003 | 63.2R233.15L | CHIP RES 2.2 J 1/10W 0603 | R2_SA;HF_SA;G_SA; | TA-I ; RALEC ; YAGEO ; WALSIN | RM06JTN2R2 ; RTT032R2JTP ; RC0603JR-072R2L ; WR06X2R2JTL | Multiple |  | Purchase | SMT | 2 | PCS | R28 R499 |
| 3 | B55.01102.M003 | 63.30234.1DL | CHIP RES 3K J 1/16W 0402(ROHS) | R2_SA;HF_SA;G_SA; | TA-I;RALEC;CYNTEC;YAGEO;WALSIN | RM04JTN302 ; RTT02302JTH ; RR0510S-302-JN ; RC0402JR-073KL;WR04X302JTL | Multiple |  | Purchase | SMT | 1 | PCS | R240 |
| 3 | B55.01102.M003 | 63.62334.1DL | CHIP RES 62K J 1/16W 0402 | R2_SA;HF_SA;G_SA; | TA-I ; RALEC ; CYNTEC ; YAGEO | RM04JTN623 ; RTT02623JTH ; RR0510S-623-JN ; RC0402JR-0762KL | Multiple |  | Purchase | SMT | 1 | PCS | R401 |
| 3 | B55.01102.M003 | 63.75334.1DL | CHIP RES 75K J 1/16W 0402 | R2_SA;HF_SA;G_SA; | TA-I ;  RALEC ; CYNTEC;YAGEO | RM04JTN753 ; RTT02753JTH ; RR-0510S-753-JN ; RC0402JR-0775KL | Multiple |  | Purchase | SMT | 1 | PCS | R609 |
| 3 | B55.01102.M003 | 63.82234.1DL | CHIP RES 8.2K J 1/16W 0402 | R2_SA;HF_SA;G_SA; | TA-I;RALEC;CYNTEC;YAGEO;WALSIN | RM04JTN822 ; RTT02822JTH ; RR0510S-822-JN ; RC0402JR-078K2L;WR04X822JTL | Multiple |  | Purchase | SMT | 1 | PCS | R356 |
| 3 | B55.01102.M003 | 63.R0031.16L | CHIP RES 0 J 1/8W 0805 | R2_SA;HF_SA;G_SA; | TAI;RALEC;YAGEO;WALSIN | RM10JTN0 ; RTT05000JTP ; RC0805JR-070RL ; WR08X000PTL | Multiple |  | Purchase | SMT | 8 | PCS | R24 R26 R382 R509 R510 R511 R527 R84 |
| 3 | B55.01102.M003 | 63.R0034.1DL | CHIP RES 0 J 1/16W 0402 | R2_SA;HF_SA;G_SA; | TAI;RALEC;CYNTEC;YAGEO;WALSIN | RM04JTN0;RTT02000JTH;RR0510X-000-XN;RC0402JR-070RL;WR04X000PTL | Multiple |  | Purchase | SMT | 95 | PCS | R100 R101 R102 R103 R105 R12 R121 R13 R132 R133 R156 R169 R174 R177 R193 R202 R205 R206 R207 R210 R211 R243 R25 R288 R289 R290 R292 R293 R294 R295 R296 R297 R298 R299 R314 R315 R325 R326 R327 R328 R341 R347 R348 R351 R354 R355 R372 R383 R386 R387 R402 R410 R415 R423 R424 R433 R434 R442 R444 R446 R461 R473 R486 R497 R498 R517 R525 R529 R535 R536 R538 R539 R540 R541 R542 R545 R558 R572 R574 R576 R578 R579 R582 R585 R601 R603 R692 R75 R76 R80 R88 R89 R90 R92 R95 |
| 3 | B55.01102.M003 | 64.10006.6DL | CHIP RES 100 D 1/16W 0402 | R2_SA;HF_SA;G_SA; | RALEC;TAI;CYNTEC;YAGEO | RTT021000DTH;RM04DTN1000;RR0510P-101-DN;RC0402DR-07100RL | Multiple |  | Purchase | SMT | 2 | PCS | R435 R436 |
| 3 | B55.01102.M003 | 64.10015.6DL | CHIP RES 1K F 1/16W 0402 | R2_SA;HF_SA;G_SA; | TA-I;RALEC;CYNTEC;YAGEO;WALSIN | RM04FTN1001 ; RTT021001FTH ; RR0510S-102-FN ; RC0402FR-071KL;WR04X1001FTL | Multiple |  | Purchase | SMT | 17 | PCS | R10 R321 R322 R323 R352 R353 R359 R380 R400 R445 R66 R67 R68 R69 R70 R71 R9 |
| 3 | B55.01102.M003 | 64.10025.6DL | CHIP RES 10K F 1/16W 0402 | R2_SA;HF_SA;G_SA; | TA-I;RALEC;CYNTEC;YAGEO;WALSIN | RM04FTN1002 ; RTT021002FTH ; RR0510S-103-FN ; RC0402FR-0710KL;WR04X1002FTL | Multiple |  | Purchase | SMT | 71 | PCS | R1 R120 R129 R139 R149 R171 R172 R178 R2 R213 R214 R215 R216 R217 R218 R219 R220 R222 R223 R225 R226 R227 R228 R229 R230 R231 R232 R237 R241 R246 R252 R253 R254 R255 R256 R257 R269 R27 R270 R271 R272 R273 R274 R286 R291 R3 R300 R303 R307 R308 R309 R312 R373 R375 R394 R398 R403 R404 R483 R484 R487 R488 R500 R518 R528 R555 R557 R606 R608 R693 R97 |
| 3 | B55.01102.M003 | 64.10035.6DL | CHIP RES 100K F 1/16W 0402 | R2_SA;HF_SA;G_SA; | TA-I;RALEC;CYNTEC;YAGEO;WALSIN | RM04FTN1003 ; RTT021003FTH ; RR0510S-104-FN ; RC0402FR-07100KL;WR04X1003FTL | Multiple |  | Purchase | SMT | 2 | PCS | R496 R532 |
| 3 | B55.01102.M003 | 64.10R05.16L | CHIP RES 10 F 1/8W 0805(ROHS) | R2_SA;HF_SA;G_SA; | TAI;YAGEO;RALEC | RM10FTN10R0;RC0805FR-0710RL;RTT0510R0FTP | Multiple |  | Purchase | SMT | 1 | PCS | R526 |
| 3 | B55.01102.M003 | 64.10R05.55L | CHIP RES 10 F 1/10W 0603 | R2_SA;HF_SA;G_SA; | TA-I;RALEC;YAGEO;WALSIN | RM06FTN10R0 ; RTT0310R0FTP ; RC0603FR-0710RL;WR06X10R0FTL | Multiple |  | Purchase | SMT | 2 | PCS | R29 R512 |
| 3 | B55.01102.M003 | 64.10R05.6DL | CHIP RES 10 F 1/16W 0402 | R2_SA;HF_SA;G_SA; | TAI;RALEC;CYNTEC;YAGEO;WALSIN | RM04FTN10R0;RTT0210R0FTH;RR0510S-100-FN;RC0402FR-0710RL;WR04X10R0FTL | Multiple |  | Purchase | SMT | 17 | PCS | R11 R151 R152 R153 R154 R155 R277 R278 R279 R280 R281 R282 R283 R519 R520 R522 R523 |
| 3 | B55.01102.M003 | 64.11025.6DL | CHIP RES 11K F 1/16W 0402 | R2_SA;HF_SA;G_SA; | TA-I ; RALEC ; CYNTEC ; YAGEO;WALSIN | RM04FTN1102 ; RTT021102FTH ; RR0510S-1102-FN ; RC0402FR-0711KL;WR04X1102FTL | Multiple |  | Purchase | SMT | 1 | PCS | R543 |
| 3 | B55.01102.M003 | 64.12115.6DL | CHIP RES 1.21K F 1/16W 0402 | R2_SA;HF_SA;G_SA; | TA-I;RALEC;CYNTEC;YAGEO;WALSIN | RM04FTN1211;RTT021211FTH;RR0510S-1211-FN;RC0402FR-071K21L;WR04X1211FTL | Multiple |  | Purchase | SMT | 1 | PCS | R490 |
| 3 | B55.01102.M003 | 64.15005.6DL | CHIP RES 150 F 1/16W 0402 | R2_SA;HF_SA;G_SA; | TAI;RALEC;CYNTEC;YAGEO;WALSIN | RM04FTN1500 ; RTT021500FTH ; RR0510S-1500-FN ; RC0402FR-07150RL;WR04X1500FTL | Multiple |  | Purchase | SMT | 3 | PCS | R238 R239 R94 |
| 3 | B55.01102.M003 | 64.15015.6DL | CHIP RES 1.5K F 1/16W 0402 | R2_SA;HF_SA;G_SA; | TA-I;RALEC;CYNTEC;YAGEO;WALSIN | RM04FTN1501 ; RTT021501FTH ; RR0510S-152-FN ; RC0402FR-071K5L;WR04X1501FTL | Multiple |  | Purchase | SMT | 1 | PCS | R378 |
| 3 | B55.01102.M003 | 64.15025.6DL | CHIP RES 15K F 1/16W 0402 | R2_SA;HF_SA;G_SA; | TA-I;RALEC;CYNTEC;YAGEO | RM04FTN1502;RTT021502FTH;RR0510S-153-FN;RC0402FR-0715KL | Multiple |  | Purchase | SMT | 1 | PCS | R377 |
| 3 | B55.01102.M003 | 64.19125.6DL | CHIP RES 19.1K F 1/16W 0402 | R2_SA;HF_SA;G_SA; | TA-I;RALEC;CYNTEC;YAGEO | RM04FTN1912;RTT021912FTH;RR0510S-1912-FN;RC0402FR-0719K1L | Multiple |  | Purchase | SMT | 1 | PCS | R492 |
| 3 | B55.01102.M003 | 64.19625.6DL | CHIP RES 19.6K F 1/16W 0402 | R2_SA;HF_SA;G_SA; | RALEC ; CYNTEC ; TA-I ; YAGEO | RTT021962FTH ; RR0510S-1962-FN ; RM04FTN1962 ; RC0402FR-0719K6L | Multiple |  | Purchase | SMT | 1 | PCS | R501 |
| 3 | B55.01102.M003 | 64.1R005.16L | CHIP RES 1 F 1/8W 0805 | R2_SA;HF_SA;G_SA; | TAI;YAGEO;RALEC;WALSIN | RM10FTN1R00;RC0805FR-071RL;RTT051R00FTP;WR08W1R00FTL | Multiple |  | Purchase | SMT | 1 | PCS | R479 |
| 3 | B55.01102.M003 | 64.20035.6DL | CHIP RES 200K F 1/16W 0402 | R2_SA;HF_SA;G_SA; | TA-I;RALEC;CYNTEC;YAGEO;WALSIN | RM04FTN2003 ; RTT022003FTH ; RR0510S-204-FN ; RC0402FR-07200KL;WR04X2003FTL | Multiple |  | Purchase | SMT | 8 | PCS | R411 R416 R425 R426 R437 R438 R439 R441 |
| 3 | B55.01102.M003 | 64.22015.6DL | CHIP RES 2.2K F 1/16W 0402 | R2_SA;HF_SA;G_SA; | TA-I;RALEC;CYNTEC;YAGEO | RM04FTN2201;RTT022201FTH;RR0510S-222-FN;RC0402FR-072K2L | Multiple |  | Purchase | SMT | 20 | PCS | R179 R180 R181 R182 R183 R184 R185 R187 R188 R189 R190 R191 R192 R194 R195 R196 R197 R200 R203 R204 |
| 3 | B55.01102.M003 | 64.22105.6DL | CHIP RES 221 F 1/16W 0402 | R2_SA;HF_SA;G_SA; | TA-I;RALEC;CYNTEC;YAGEO | RM04FTN2210;RTT022210FTH;RR0510S-2210-FN;RC0402FR-07221RL | Multiple |  | Purchase | SMT | 2 | PCS | R489 R491 |
| 3 | B55.01102.M003 | 64.22635.6DL | CHIP RES 226K F 1/16W 0402 | R2_SA;HF_SA;G_SA; | TA-I ; RALEC ; CYNTEC ; YAGEO | RM04FTN2263 ; RTT022263FTH ; RR0510S-2263-FN ; RC0402FR-07226KL | Multiple |  | Purchase | SMT | 1 | PCS | R22 |
| 3 | B55.01102.M003 | 64.27015.6DL | CHIP RES 2.7K F 1/16W 0402 | R2_SA;HF_SA;G_SA; | TAI;RALEC;CYNTEC;YAGEO | RM04FTN2701;RTT022701FTH;RR0510S-2701-FN;RC0402FR-072K7L | Multiple |  | Purchase | SMT | 1 | PCS | R514 |
| 3 | B55.01102.M003 | 64.28715.6DL | CHIP RES 2.87K F 1/16W 0402 | R2_SA;HF_SA;G_SA; | TA-I;RALEC;CYNTEC;YAGEO | RM04FTN2871;RTT022871FTH;RR0510S-2871-FN;RC0402FR-072K87L | Multiple |  | Purchase | SMT | 1 | PCS | R98 |
| 3 | B55.01102.M003 | 64.2R205.55L | CHIP RES 2.2 F 1/10W 0603 | R2_SA;HF_SA;G_SA; | TAI;YAGEO;RALEC;WALSIN | RM06FTN2R20;RC0603FR-072R2L;RTT032R20FTP;WR06W2R20FTL | Multiple |  | Purchase | SMT | 3 | PCS | R381 R440 R515 |
| 3 | B55.01102.M003 | 64.30115.6DL | CHIP RES 3.01K F 1/16W 0402 | R2_SA;HF_SA;G_SA; | TA-I;RALEC;CYNTEC;YAGEO;WALSIN | RM04FTN3011 ; RTT023011FTH ; RR0510S-3011-FN ; RC0402FR-073K01L;WR04X3011FTL | Multiple |  | Purchase | SMT | 1 | PCS | R115 |
| 3 | B55.01102.M003 | 64.34025.6DL | CHIP RES 34K F 1/16W 0402 | R2_SA;HF_SA;G_SA; | TA-I ; RALEC ; CYNTEC ; YAGEO | RM04FTN3402 ; RTT023402FTH ; RR0510S-3402-FN ; RC0402FR-0734KL | Multiple |  | Purchase | SMT | 1 | PCS | R140 |
| 3 | B55.01102.M003 | 64.35715.6DL | CHIP RES 3.57K F 1/16W 0402 | R2_SA;HF_SA;G_SA; | TA-I;RALEC;CYNTEC;YAGEO | RM04FTN3571;RTT023571FTH;RR0510S-3571-FN;RC0402FR-073K57L | Multiple |  | Purchase | SMT | 1 | PCS | R99 |
| 3 | B55.01102.M003 | 64.38325.6DL | CHIP RES 38.3K F 1/16W 0402 | R2_SA;HF_SA;G_SA; | TAI;RALEC;CYNTEC;YAGEO | RM04FTN3832;RTT023832FTH;RR0510S-3832-FN;RC0402FR-0738K3L | Multiple |  | Purchase | SMT | 1 | PCS | R521 |
| 3 | B55.01102.M003 | 64.44225.6DL | CHIP RES 44.2K F 1/16W 0402 | R2_SA;HF_SA;G_SA; | TAI;RALEC;CYNTEC;YAGEO;WALSIN | RM04FTN4422;RTT024422FTH;RR0510S-4422-FN;RC0402FR-0744K2L;WR04X4422FTL | Multiple |  | Purchase | SMT | 1 | PCS | R513 |
| 3 | B55.01102.M003 | 64.45305.6DL | CHIP RES 453 F 1/16W 0402 | R2_SA;HF_SA;G_SA; | TA-I;RALEC;CYNTEC;YAGEO;WALSIN | RM04FTN4530 ; RTT024530FTH ; RR0510S-4530-FN ; RC0402FR-07453RL;WR04X4530FTL | Multiple |  | Purchase | SMT | 1 | PCS | R493 |
| 3 | B55.01102.M003 | 64.45315.6DL | CHIP RES 4.53K F 1/16W 0402 | R2_SA;HF_SA;G_SA; | TA-I;RALEC;CYNTEC;YAGEO;WALSIN | RM04FTN4531 ; RTT024531FTH ; RR0510S-4531-FN ; RC0402FR-074K53L;WR04X4531FTL | Multiple |  | Purchase | SMT | 2 | PCS | R4 R8 |
| 3 | B55.01102.M003 | 64.45325.6DL | CHIP RES 45.3K F 1/16W 0402 | R2_SA;HF_SA;G_SA; | TA-I ; RALEC ; CYNTEC ; YAGEO;WALSIN | RM04FTN4532 ; RTT024532FTH ; RR0510S-4532-FN ; RC0402FR-0745K3L;WR04X4532FTL | Multiple |  | Purchase | SMT | 1 | PCS | R548 |
| 3 | B55.01102.M003 | 64.47015.6DL | CHIP RES 4.7K F 1/16W 0402 | R2_SA;HF_SA;G_SA; | TA-I;RALEC;CYNTEC;YAGEO;WALSIN | RM04FTN4701;RTT024701FTH;RR0510S-472-FN;RC0402FR-074K7L;WR04X4701FTL | Multiple |  | Purchase | SMT | 80 | PCS | R126 R127 R128 R130 R135 R141 R142 R143 R144 R145 R146 R147 R198 R199 R201 R233 R234 R235 R242 R244 R258 R259 R260 R261 R262 R263 R264 R265 R266 R267 R268 R275 R276 R317 R332 R333 R335 R345 R346 R36 R360 R362 R363 R37 R374 R376 R39 R397 R40 R41 R42 R43 R44 R443 R46 R48 R49 R50 R51 R52 R53 R54 R546 R55 R56 R57 R58 R59 R599 R60 R602 R604 R605 R61 R64 R65 R77 R78 R79 R83 |
| 3 | B55.01102.M003 | 64.47515.6DL | CHIP RES 4.75K F 1/16W 0402 | R2_SA;HF_SA;G_SA; | TA-I;RALEC;CYNTEC;YAGEO | RM04FTN4751;RTT024751FTH;RR0510S-4751-FN;RC0402FR-074K75L | Multiple |  | Purchase | SMT | 28 | PCS | R106 R107 R108 R109 R110 R111 R112 R113 R114 R116 R117 R119 R122 R123 R136 R137 R138 R150 R212 R236 R301 R302 R34 R35 R350 R47 R85 R86 |
| 3 | B55.01102.M003 | 64.47535.6DL | CHIP RES 475K F 1/16W 0402 | R2_SA;HF_SA;G_SA; | TA-I;RALEC;CYNTEC;YAGEO | RM04FTN4753;RTT024753FTH;RR0510S-4753-FN;RC0402FR-07475KL | Multiple |  | Purchase | SMT | 2 | PCS | R31 R508 |
| 3 | B55.01102.M003 | 64.49925.6DL | CHIP RES 49.9K F 1/16W 0402 | R2_SA;HF_SA;G_SA; | TA-I ; RALEC ; CYNTEC ; YAGEO ; WALSIN | RM04FTN4992 ; RTT024992FTH ; RR0510S-4992-FN ; RC0402FR-0749K9L ; WR04X4992FTL | Multiple |  | Purchase | SMT | 2 | PCS | R550 R551 |
| 3 | B55.01102.M003 | 64.51025.6DL | CHIP RES 51K F 1/16W 0402 | R2_SA;HF_SA;G_SA; | TA-I ; RALEC ; CYNTEC ; YAGEO;WALSIN | RM04FTN5102 ; RTT025102FTH ; RR0510S-513-FN ; RC0402FR-0751KL;WR04X5102FTL | Multiple |  | Purchase | SMT | 1 | PCS | R504 |
| 3 | B55.01102.M003 | 64.6342D.6DL | CHIP RES 63.4K B 1/16W 0402 | R2_SA;HF_SA;G_SA; | TAI ; RALEC ; CYNTEC ; YAGEO | RB04BTS6342 ; RTX026342BETH ; RR0510Q-6342-BN ; RT0402BRE0763K4L | Multiple |  | Purchase | SMT | 1 | PCS | R20 |
| 3 | B55.01102.M003 | 64.69825.6DL | CHIP RES 69.8K F 1/16W 0402 | R2_SA;HF_SA;G_SA; | TA-I;RALEC;CYNTEC;YAGEO | RM04FTN6982;RTT026982FTH;RR0510S-6982-FN;RC0402FR-0769K8L | Multiple |  | Purchase | SMT | 2 | PCS | R320 R485 |
| 3 | B55.01102.M003 | 64.73215.6DL | CHIP RES 7.32K F 1/16W 0402 | R2_SA;HF_SA;G_SA; | TA-I;RALEC;CYNTEC;YAGEO;WALSIN | RM04FTN7321;RTT027321FTH;RR0510S-7321-FN;RC0402FR-077K32L;WR04X7321FTL | Multiple |  | Purchase | SMT | 1 | PCS | R494 |
| 3 | B55.01102.M003 | 64.80615.6DL | CHIP RES 8.06K F 1/16W 0402 | R2_SA;HF_SA;G_SA; | TA-I;RALEC;CYNTEC;YAGEO;WALSIN | RM04FTN8061;RTT028061FTH;RR0510S-8061-FN;RC0402FR-078K06L;WR04X8061FTL | Multiple |  | Purchase | SMT | 1 | PCS | R399 |
| 3 | B55.01102.M003 | 64.R0005.6DL | CHIP RES 0 F 1/16W 0402 | R2_SA;HF_SA;G_SA; | RALEC;CYNTEC;TAI;YAGEO;WALSIN | RTT020000FTH;RR0510S-000-FNH;RM04FTN0;RC0402FR-070RL;WR04X000 PTL | Multiple |  | Purchase | SMT | 2 | PCS | R477 R478 |
| 3 | B55.01102.M003 | 64.R5105.55L | CHIP RES 0.51 F 1/10W 0603 L/F | R2_SA;HF_SA;G_SA; | RALEC ; TA-I ; YAGEO ; WALSIN | RTT03R510FTP ; RL06FTNR510 ; RL0603FR-070R51L ; WW06XR510FTL | Multiple |  | Purchase | SMT | 15 | PCS | R134 R157 R158 R159 R160 R161 R162 R163 R164 R165 R166 R167 R168 R284 R285 |
| 3 | B55.01102.M003 | 68.00084.771 | CHIP BEAD BLM41PG600SN1L MURAT | R2_SA;HF_SA; | MURATA | BLM41PG600SN1L | Multiple |  | Purchase | SMT | 2 | PCS | L30 L32 |
| A | B55.01102.M003 | 68.00214.071 | CHIP BEAD HCB4516KF-600T60(LF) | R2_SA;HF_SA; | TAITECH | HCB4516KF-600T60 |  |  | Purchase |  |  |  |  |
| A | B55.01102.M003 | 68.00376.031 | CHIP BEAD BCMS451616A600 | R2_SA;HF_SA; | MAXECHO | BCMS451616A600 |  |  | Purchase |  |  |  |  |
| 3 | B55.01102.M003 | 68.00084.831 | CHIP BEAD BLM21PG220SN1D (LF) | R2_SA;HF_SA; | MURATA | BLM21PG220SN1D | Multiple |  | Purchase | SMT | 2 | PCS | L28 L6 |
| A | B55.01102.M003 | 68.00216.081 | CHIP BEAD HCB2012KF-220T60 | R2_SA;HF_SA; | TAITECH | HCB2012KF-220T60 |  |  | Purchase |  |  |  |  |
| 3 | B55.01102.M003 | 68.00224.051 | CHIP BEAD MPZ2012S300AT TDK | R2_SA;HF_SA; | TDK | MPZ2012S300AT | Multiple |  | Purchase | SMT | 14 | PCS | L10 L11 L12 L13 L14 L15 L16 L17 L18 L26 L35 L7 L8 L9 |
| A | B55.01102.M003 | 068.00002.0091 | CHIP BEAD BLM21SN300SN1D MURATA | R2_SA;HF_SA; | MURATA | BLM21SN300SN1D |  |  | Purchase |  |  |  |  |
| 3 | B55.01102.M003 | 68.00224.201 | CHIP BEAD MPZ2012S601AT TDK | R2_SA;HF_SA; | TDK | MPZ2012S601AT | Single |  | Purchase | SMT | 12 | PCS | L1 L19 L2 L20 L21 L22 L23 L24 L25 L3 L4 L5 |
| 3 | B55.01102.M003 | 68.00395.001 | CHIP BEAD 0181 28F0181-1SR-10 | R2_SA;HF_SA; | LAIRD | 28F0181-1SR-10 | Single |  | Purchase | SMT | 1 | PCS | L27 |
| 3 | B55.01102.M003 | 68.2R21A.20B | CHIP CHOKE 2.2U PCMB063T-2R2MS | R2_SA;HF_SA; | CYNTEC | PCMB063T-2R2MS | Multiple |  | Purchase | SMT | 1 | PCS | L29 |
| A | B55.01102.M003 | 68.2R210.20P | CHIP CHOKE 2.2UH MPLCG0630L2R2 | R2_SA;HF_SA; | NEC;TOKIN | MPLCG0630L2R2 |  |  | Purchase |  |  |  |  |
| A | B55.01102.M003 | 68.2R21E.10X | CHIP IND 2.2UH M SPM6530T-2R2M | R2_SA;HF_SA; | TDK | SPM6530T-2R2M |  |  | Purchase |  |  |  |  |
| 3 | B55.01102.M003 | 68.3R310.20V | CHIP CHOKE 3.3UH PCMB063T-3R3MS | R2_SA;HF_SA; | CYNTEC | PCMB063T-3R3MS | Multiple |  | Purchase | SMT | 1 | PCS | L34 |
| A | B55.01102.M003 | 68.3R31A.10V | CHIP IND 3.3UH MMD-06CZ-3R3M-V | R2_SA;HF_SA;G_SA; | MAGLAYER | MMD-06CZ-3R3M-V1W |  |  | Purchase |  |  |  |  |
| A | B55.01102.M003 | 68.3R31A.20D | CHIP CHOKE 3.3UH M PCMB065T-3R3MS | R2_SA;HF_SA; | CYNTEC | PCMB065T-3R3MS |  |  | Purchase |  |  |  |  |
| 3 | B55.01102.M003 | 68.R2410.20A | CHIP CHOKE 0.24UH PCME064T-R24MS1R007 | R2_SA;HF_SA; | CYNTEC | PCME064T-R24MS1R007 | Multiple |  | Purchase | SMT | 1 | PCS | L33 |
| A | B55.01102.M003 | 68.R2410.101 | CHIP IND 0.24UH MMD-06DZNR24MGC1W | R2_SA;HF_SA; | MAGLAYER | MMD-06DZNR24MGC1W |  |  | Purchase |  |  |  |  |
| A | B55.01102.M003 | 68.R2410.201 | CHIP CHOKE 0.24UH ETQP4LR24AFM | R2_SA;HF_SA; | PANASONIC | ETQP4LR24AFM |  |  | Purchase |  |  |  |  |
| 3 | B55.01102.M003 | 71.03X48.00U | IC SAS EXPANDER SAS3X48 FPB22GU 1020P | R2_SA;HF_SA; | LSI | SAS3X48C1-DB(500021061) | Single |  | Purchase | SMT | 1 | PCS | U1 |
| 3 | B55.01102.M003 | 72.24C64.I01 | IC EEPROM CAT24C64WI-GT3 SOIC 8P | R2_SA;HF_SA;G_SA; | ON | CAT24C64WI-GT3 | Multiple |  | Purchase | SMT | 1 | PCS | U27 |
| A | B55.01102.M003 | 72.24C64.K01 | IC EEPROM M24C64-RMN6TP SOIC 8P | R2_SA;HF_SA; | STMICROELECTRONICS INC | M24C64-RMN6TP |  |  | Purchase |  |  |  |  |
| 3 | B55.01102.M003 | 72.24C64.K01 | IC EEPROM M24C64-RMN6TP SOIC 8P | R2_SA;HF_SA; | STMICROELECTRONICS INC | M24C64-RMN6TP | Multiple |  | Purchase | SMT | 1 | PCS | U29 |
| A | B55.01102.M003 | 072.02464.0A01 | IC EEPROM FM24C64D-SO-T-G SOP 8P | R2_SA;HF_SA; | FUDAN | FM24C64D-SO-T-G |  |  | Purchase |  |  |  |  |
| 3 | B55.01102.M003 | 73.00102.007 | IC TRANSLATOR TXS0102DCUR VSSOP 8P | R2_SA;HF_SA; | TI | TXS0102DCUR | Multiple |  | Purchase | SMT | 3 | PCS | U20 U21 U22 |
| A | B55.01102.M003 | 71.09406.001 | IC I2C/SMBUS TCA9406DCUR US8 | R2_SA;HF_SA; | TI | TCA9406DCUR |  |  | Purchase |  |  |  |  |
| 3 | B55.01102.M003 | 73.01G07.EHH | IC CMOS 74LVC1G07DCKR SC70-5 | R2_SA;HF_SA; | TI | SN74LVC1G07DCKR | Multiple |  | Purchase | SMT | 1 | PCS | U9 |
| A | B55.01102.M003 | 73.01G07.0HG | IC CMOS 74LVC1G07GW,125 SOT353-1 | R2_SA;HF_SA; | NEXPERIA | 74LVC1G07GW,125 |  |  | Purchase |  |  |  |  |
| 3 | B55.01102.M003 | 73.01G11.AHH | IC CMOS SN74LVC1G11DCKR DCK | R2_SA;HF_SA;G_SA; | TI | SN74LVC1G11DCKR | Multiple |  | Purchase | SMT | 1 | PCS | U42 |
| A | B55.01102.M003 | 073.74111.000J | IC CMOS GATE U74LVC1G11G-AL6-R SOT363 6P | R2_SA;HF_SA; | UTC | U74LVC1G11G-AL6-R |  |  | Purchase |  |  |  |  |
| 3 | B55.01102.M003 | 73.1G126.DHG | IC CMOS SN74LVC1G126DCKR SC70 | R2_SA;HF_SA; | TI | SN74LVC1G126DCKR | Multiple |  | Purchase | SMT | 1 | PCS | U48 |
| A | B55.01102.M003 | 073.7S126.000G | IC CMOS TC7SZ126FU,LJ(CT SSOP5-P-0.65A | R2_SA;HF_SA; | TOSHIBA | TC7SZ126FU,LJ(CT |  |  | Purchase |  |  |  |  |
| A | B55.01102.M003 | 73.7S126.AAH | IC CMOS NC7SZ126P5X SC70-5 | R2_SA;HF_SA; | FAIRCHILD | NC7SZ126P5X |  |  | Purchase |  |  |  |  |
| 3 | B55.01102.M003 | 73.8T245.B29 | IC XCVR SN74LVC8T245DGVR TVSOP | R2_SA;HF_SA; | TI | SN74LVC8T245DGVR | Single |  | Purchase | SMT | 3 | PCS | U12 U14 U24 |
| 3 | B55.01102.M003 | 74.00235.033 | IC S.R VT235WFQX-ADJ QFN 19P | R2_SA;HF_SA; | VOLTERRA | VT235WFQX-ADJ | Single |  | Purchase | SMT | 1 | PCS | U6 |
| 3 | B55.01102.M003 | 74.01015.049 | IC CONV ADS1015IDGSR MSOP 10P | R2_SA;HF_SA; | TI | ADS1015IDGSR | Single |  | Purchase | SMT | 2 | PCS | U25 U26 |
| 3 | B55.01102.M003 | 74.51219.A73 | IC BUCK CTRL TPS51219RTER(MP) QFN 16P | R2_SA;HF_SA; | TI | TPS51219RTER | Single |  | Purchase | SMT | 1 | PCS | U8 |
| 3 | B55.01102.M003 | 74.53318.073 | IC PWR CTRL TPS53318DQPR QFN 22P | R2_SA;HF_SA; | TI | TPS53318DQPR | Single |  | Purchase | SMT | 2 | PCS | U10 U11 |
| 3 | B55.01102.M003 | 74.74801.A33 | IC LDO TPS74801RGW QFN 20P | R2_SA;HF_SA; | TI | TPS74801RGW | Single |  | Purchase | SMT | 1 | PCS | U4 |
| 3 | B55.01102.M003 | 74.78M05.03C | IC A.R UA78M05CDCYRG3 SOT-223 | R2_SA;HF_SA; | TI | UA78M05CDCYRG3 | Single |  | Purchase | SMT | 1 | PCS | U7 |
| 3 | B55.01102.M003 | 78.10222.20L | CHIP CAP C 1000P 25V K0201 X7R | R2_SA;HF_SA;G_SA; | MURATA;TDK;PHYCOMP;DARFON;WALSIN | GRM033R71E102KA01D;C0603X7R1E102KT00NN;223891815623;C0603X7R102KFT;0201B102K250CT | Multiple |  | Purchase | SMT | 9 | PCS | C123 C124 C125 C126 C127 C187 C188 C189 C190 |
| 3 | B55.01102.M003 | 78.10224.2FL | CHIP CAP C 1000P 50V K0402 X7R | R2_SA;R_SA;HF_SA;G_SA; | AVX;DARFON;MURATA;PHYCOMP;SAMSUNG;TAIYO;MURATA;AVX;YAGEO | CM05X7R102K50AH;C1005X7R102KGT;GRM155R71H102KA01D;223858715623;CL05B102KB5NNNC;UMK105B7102KV-F;WBM155R71H102KA01D;04025C102KAT2A;CC0402KRX7R9BB102 | Multiple |  | Purchase | SMT | 22 | PCS | C444 C445 C446 C447 C448 C449 C450 C451 C494 C495 C496 C497 C498 C499 C500 C501 C611 C615 C618 C625 C640 C655 |
| 3 | B55.01102.M003 | 78.10322.2FL | CHIP CAP C 0.01U 25V K0402 X7R | R2_SA;HF_SA;G_SA; | AVX;DARFON;MURATA;PHYCOMP;SAMSUNG;TAIYO;TDK;MURATA;YAGEO | 04023C103KAT2A;C1005X7R103KFT;GRM155R71E103KA01D;223891715636;CL05B103KA5NNNC;TMK105BJ103KV-F;C1005X7R1E103KT000F;WBM155R71E103KA01D;CC0402KRX7R8BB103 | Multiple |  | Purchase | SMT | 7 | PCS | C113 C346 C529 C612 C613 C648 C662 |
| 3 | B55.01102.M003 | 78.10420.50L | CHIP CAP C 0.1U 6.3V K0201 X5R | R2_SA;HF_SA;G_SA; | MURATA;AVX;DARFON;WALSIN;MATSUKI;TAIYO;SAMSUNG;SAMSUNG;YAGEO | GRM033R60J104KE19D;02016D104KAT2A;C0603X5R104KCT;0201X104K6R3CT;MAG01X5R0J104K;JMK063BJ104KP-F;CL03A104KQ3NNNH;CL03A104KQ3NNNHC;CC0201KRX5R5BB104 | Multiple |  | Purchase | SMT | 203 | PCS | C128 C129 C130 C131 C132 C133 C134 C135 C136 C137 C138 C139 C140 C141 C142 C143 C144 C145 C146 C147 C148 C149 C150 C151 C152 C153 C154 C155 C156 C157 C158 C159 C160 C161 C162 C163 C164 C165 C166 C167 C168 C169 C170 C171 C172 C173 C174 C175 C176 C177 C178 C179 C180 C181 C182 C195 C199 C203 C207 C211 C230 C231 C232 C233 C237 C238 C239 C240 C244 C245 C246 C247 C251 C252 C253 C254 C258 C259 C260 C261 C265 C266 C267 C268 C269 C271 C272 C273 C276 C278 C279 C280 C282 C284 C285 C286 C289 C291 C292 C293 C297 C299 C300 C301 C304 C306 C307 C308 C386 C387 C388 C389 C390 C391 C392 C393 C417 C418 C419 C420 C421 C422 C423 C424 C425 C426 C427 C428 C429 C430 C431 C432 C433 C434 C435 C436 C437 C438 C439 C440 C441 C442 C443 C452 C453 C454 C455 C456 C457 C458 C459 C460 C461 C462 C463 C464 C465 C466 C467 C468 C469 C470 C471 C472 C473 C474 C475 C476 C477 C478 C479 C480 C481 C488 C489 C490 C491 C492 C493 C512 C513 C514 C531 C536 C537 C538 C539 C540 C578 C579 C580 C581 C582 C583 C584 C585 C586 C587 C588 C589 C590 C591 C592 |
| 3 | B55.01102.M003 | 78.10421.2FL | CHIP CAP C 0.1U 16V K0402 X7R | R2_SA;HF_SA;G_SA; | DARFON;MURATA;PHYCOMP;SAMSUNG;TAIYO;WALSIN;YAGEO | C1005X7R104KET;GRM155R71C104KA88D;223878715649;CL05B104KO5NNNC;EMK105B7104KV-F;0402B104K160CT;CC0402KRX7R7BB104 | Multiple |  | Purchase | SMT | 99 | PCS | C101 C104 C112 C114 C116 C117 C212 C215 C216 C217 C218 C219 C220 C221 C222 C223 C224 C225 C226 C345 C349 C350 C354 C358 C362 C366 C370 C374 C375 C376 C380 C381 C382 C397 C398 C399 C400 C401 C402 C403 C404 C502 C503 C504 C505 C506 C507 C508 C509 C510 C515 C516 C517 C519 C521 C523 C524 C525 C526 C528 C530 C532 C533 C534 C541 C542 C545 C548 C549 C550 C551 C552 C557 C558 C559 C560 C561 C562 C570 C571 C575 C576 C577 C594 C596 C600 C604 C641 C647 C674 C689 C692 C693 C705 C731 C732 C733 C97 C98 |
| 3 | B55.01102.M003 | 78.10424.2BL | CHIP CAP C 0.1U 50V K0603 X7R | R2_SA;HF_SA;G_SA; | MURATA;AVX;PHYCOMP;SAMSUNG;DARFON;WALSIN;YAGEO | GRM188R71H104KA93D;06035C104KAT2A;223858615649;CL10B104KB8NNNC;C1608X7R104KGT;0603B104K500CT;CC0603KRX7R9BB104 | Multiple |  | Purchase | SMT | 12 | PCS | C651 C652 C653 C656 C660 C663 C664 C672 C673 C675 C697 C713 |
| 3 | B55.01102.M003 | 78.10510.5SL | CHIP CAP C 1U 6.3V M0201 X5R | R2_SA;HF_SA;G_SA; | MURATA;DARFON;TAIYO;SAMSUNG;AVX;WALSIN;YAGEO | GRM033R60J105MEA2D;C0603X5R105MCT;JDK063BJ105MP-FD;CL03A105MQ3CSNH;CV03X5R105M06AH;0201X105M6R3;CC0201MRX5R5BB105 | Multiple |  | Purchase | SMT | 23 | PCS | C194 C198 C202 C206 C210 C229 C236 C243 C250 C257 C264 C274 C281 C287 C294 C302 C309 C411 C412 C413 C414 C415 C416 |
| 3 | B55.01102.M003 | 78.10521.2BL | CHIP CAP C 1U 16V K0603 X7R | R2_SA;HF_SA;G_SA; | KEMET;MURATA;TAIYO;TDK;YAGEO;WALSIN;SAMSUNG;DARFON | C0603C105K4RAC;GRM188R71C105KA12D;EMK107B7105KA-T;C1608X7R1C105KT;CC0603KRX7R7BB105;0603B105K160CT;CL10B105KO8NNNC;C1608X7R105KET | Multiple |  | Purchase | SMT | 7 | PCS | C348 C603 C606 C638 C649 C650 C714 |
| 3 | B55.01102.M003 | 78.10522.2BL | CHIP CAP C 1U 25V K0603 X7R | R2_SA;HF_SA;G_SA; | MURATA;TAIYO;WALSIN;SAMSUNG;DARFON;YAGEO | GRM188R71E105KA12D;TMK107B7105KA-T;0603B105K250CT;CL10B105KA8NNNC;C1608X7R105KFT;CC0603KRX7R8BB105 | Multiple |  | Purchase | SMT | 5 | PCS | C619 C620 C622 C623 C646 |
| 3 | B55.01102.M003 | 78.10610.5FL | CHIP CAP C 10U 6.3V M0402 X5R | R2_SA;HF_SA;G_SA; | MURATA;YAGEO;SAMSUNG;TAIYO;DARFON;WALSIN | GRM155R60J106ME44D;CC0402MRX5R5BB106;CL05A106MQ5NUNC;JMK105CBJ106MV-F;C1005X5R106MCT;0402X106M6R3CT | Multiple |  | Purchase | SMT | 14 | PCS | C118 C119 C120 C121 C122 C183 C184 C185 C186 C193 C197 C201 C205 C209 |
| 3 | B55.01102.M003 | 78.10620.21L | CHIP CAP C 10U 6.3V K0805 X7R | R2_SA;HF_SA;G_SA; | MURATA;TAIYO;DARFON;KYOCERA | GRM21BR70J106KE76L;JMK212B7106KG-T;C2012X7R106KC;CM21X7R106K06AT | Multiple |  | Purchase | SMT | 35 | PCS | C109 C352 C356 C360 C364 C368 C372 C378 C405 C406 C407 C408 C409 C410 C597 C609 C614 C617 C627 C628 C629 C630 C684 C685 C686 C687 C688 C690 C694 C695 C703 C704 C706 C707 C708 |
| 3 | B55.01102.M003 | 78.10710.52L | CHIP CAP C 100U 6.3V M1206 X5R | R2_SA;HF_SA;G_SA; | MURATA;TAIYO;SAMSUNG;WALSIN | GRM31CR60J107ME39L;JMK316BJ107ML;CL31A107MQHNNNE;1206X107M6R3CT | Multiple |  | Purchase | SMT | 16 | PCS | C227 C234 C241 C248 C255 C262 C270 C277 C283 C290 C298 C305 C383 C394 C395 C720 |
| 3 | B55.01102.M003 | 78.15034.1FL | CHIP CAP C 15P 50V J0402 NPO | R2_SA;HF_SA;G_SA; | AVX;DARFON;MURATA;PHYCOMP;SAMSUNG;TAIYO;WALSIN;YAGEO | 04025A150JAT2A;C1005NP0150JGT;GRM1555C1H150JA01D;223886915159;CL05C150JB5NNNC;UMK105CH150JV-F;0402N150J500CT;CC0402JRNPO9BN150 | Multiple |  | Purchase | SMT | 4 | PCS | C110 C111 C334 C335 |
| 3 | B55.01102.M003 | 78.15322.2FL | CHIP CAP C 0.015U 25V K0402 X7R | R2_SA;HF_SA;G_SA; | MURATA;TDK;WALSIN;DARFON;PHYCOMP | GRM155R71E153KA61D;C1005X7R1E153KT000F;0402B153K250CT;C1005X7R153KFT;223891715638 | Multiple |  | Purchase | SMT | 1 | PCS | C522 |
| 3 | B55.01102.M003 | 78.22124.2FL | CHIP CAP C 220P 50V K0402 X7R | R2_SA;HF_SA;G_SA; | MURATA;AVX;TAIYO;PHYCOMP;DARFON;WALSIN;YAGEO | GRM155R71H221KA01D;04025C221KAT2A;UMK105B7221KV-F;223858715614;C1005X7R221KGT;0402B221K500CT;CC0402KRX7R9BB221 | Multiple |  | Purchase | SMT | 1 | PCS | C624 |
| 3 | B55.01102.M003 | 78.22322.2FL | CHIP CAP C 0.022U 25V K0402 X7R | R2_SA;HF_SA;G_SA; | MURATA;PHYCOMP;DARFON;WALSIN;YAGEO | GRM155R71E223KA61D;223891715641;C1005X7R223KFT;0402B223K250CT;CC0402KRX7R8BB223 | Multiple |  | Purchase | SMT | 1 | PCS | C737 |
| 3 | B55.01102.M003 | 78.22423.5SL | CHIP CAP C 0.22U 10V K0201 X5R | R2_SA;HF_SA;G_SA; | MURATA;DARFON;TAIYO;YAGEO;WALSIN;SAMSUNG | GRM033R61A224KE90D;C0603X5R224KDT;LMK063BJ224KP-F;CC0201KRX5R6BB224;0201X224K100CT;CL03A224KP3NNNC | Multiple |  | Purchase | SMT | 16 | PCS | C311 C312 C313 C314 C315 C316 C317 C318 C319 C320 C321 C322 C323 C324 C325 C326 |
| 3 | B55.01102.M003 | 78.22521.21L | CHIP CAP C 2.2UF 16V K0805 X7R | R2_SA;HF_SA;G_SA; | MURATA;TDK;TAIYO;DARFON;SAMSUNG;PHYCOMP;WALSIN | GRM21BR61C225KA88L;C2012X7R1C225KT000N;EMK212B7225KG-T;C2012X7R225KEP;CL21B225KOFNNNE;222278015667;0805B225K160CT | Multiple |  | Purchase | SMT | 1 | PCS | C739 |
| 3 | B55.01102.M003 | 78.22620.22L | CHIP CAP C 22U 6.3V K 1206 X7R | R2_SA;HF_SA;G_SA; | YAGEO;MURATA;KYOCERA;SAMSUNG | CC1206KKX7R5BB226;GRM31CR70J226KE19L;CM316X7R226K06AT;CL31B226KQHNNNE | Multiple |  | Purchase | SMT | 1 | PCS | C665 |
| 3 | B55.01102.M003 | 78.33421.2BL | CHIP CAP C 0.33U 16V K0603 X7R | R2_SA;HF_SA;G_SA; | MURATA;TDK;PHYCOMP;SAMSUNG;DARFON | GRM188R71C334KA01D;C1608X7R1C334KT000N;223878615656;CL10B334KO8NNNC;C1608X7R334KET | Multiple |  | Purchase | SMT | 1 | PCS | C626 |
| 3 | B55.01102.M003 | 78.47124.2FL | CHIP CAP C 470P  50V K0402 X7R | R2_SA;HF_SA;G_SA; | AVX;DARFON;MURATA;PHYCOMP;TAIYO;SAMSUNG;WALSIN;YAGEO | 04025C471KAT2A;C1005X7R471KGT;GRM155R71H471KA01D;223858715618;UMK105B7471KV-F;CL05B471KB5NNNC;0402B471K500CT;CC0402KRX7R9BB471 | Multiple |  | Purchase | SMT | 1 | PCS | C602 |
| 3 | B55.01102.M003 | 78.47222.2FL | CHIP CAP C 4700P 25V K0402 X7R | R2_SA;HF_SA;G_SA; | AVX;TDK;PHYCOMP;TAIYO;DARFON;WALSIN | 04023C472KAT2A;C1005X7R1E472KT000F;223891715632;TMK105B7472KV-F;C1005X7R472KFT;0402B472K250CT | Multiple |  | Purchase | SMT | 1 | PCS | C658 |
| 3 | B55.01102.M003 | 78.47422.2BL | CHIP CAP C 0.47U 25V K0603 X7R | R2_SA;HF_SA;G_SA; | MURATA;SAMSUNG;DARFON | GRM188R71E474KA12D;CL10B474KA8NNNC;C1608X7R474KFT | Multiple |  | Purchase | SMT | 2 | PCS | C608 C691 |
| 3 | B55.01102.M003 | 78.68224.2FL | CHIP CAP C 6800P 50V K0402 X7R | R2_SA;HF_SA;G_SA; | YAGEO;MURATA;DARFON;SAMSUNG;WALSIN | CC0402KRX7R9BB682;GRM155R71H682KA88D;C1005X7R682KGT;CL05B682KB5NNNC;0402B682K500CT | Multiple |  | Purchase | SMT | 2 | PCS | C659 C661 |
| 3 | B55.01102.M003 | 79.47719.2BL | CHIP CAP 470UF 2V EEFSX0D471X | R2_SA;HF_SA;G_SA; | PANASONIC | EEFSX0D471XE | Multiple |  | Purchase | SMT | 5 | PCS | TC1 TC2 TC3 TC6 TC7 |
| A | B55.01102.M003 | 077.54771.0001 | CHIP AP CAP 470UF 2V M7343 ESR6 | R2_SA;HF_SA; | APAQ | ACAH2R0S471E06 |  |  | Purchase |  |  |  |  |
| 3 | B55.01102.M003 | 83.01921.S70 | LED YEL GRN 19-21/G6C-BM2P1B/3T SMD | R2_SA;HF_SA;G_SA; | EVERLIGHT | 19-21/G6C-BM2P1B/3T | Multiple |  | Purchase | SMT | 3 | PCS | BLED1 LED1 LED2 |
| A | B55.01102.M003 | 83.19213.I70 | LED GRN 19-213/G6C-DH1J2AX/3T | R2_SA;HF_SA;G_SA; | EVERLIGHT | 19-213/G6C-DH1J2AX/3T |  |  | Purchase |  |  |  |  |
| 3 | B55.01102.M003 | 83.SMF15.0AH | DIODE TVS SMF15A SOD-123FL | R2_SA;HF_SA; | PANJIT | SMF15A | Multiple |  | Purchase | SMT | 1 | PCS | D37 |
| A | B55.01102.M003 | 83.00015.0AF | DIODE TVS DFLT15A-7 POWERDI123 | R2_SA;HF_SA; | DIODES | DFLT15A-7 |  |  | Purchase |  |  |  |  |
| 3 | B55.01102.M003 | 84.03904.T11 | XTOR MMBT3904 NPN SOT-23 | R2_SA;HF_SA;G_SA; | PANJIT | MMBT3904 | Multiple |  | Purchase | SMT | 1 | PCS | Q37 |
| A | B55.01102.M003 | 84.T3904.H11 | XTOR LMBT3904LT1G NPN SOT-23 | R2_SA;HF_SA;G_SA; | LRC | LMBT3904LT1G |  |  | Purchase |  |  |  |  |
| 3 | B55.01102.M003 | 84.08878.A37 | FET MOS FDS8878_G NC SO-8(HF) | R2_SA;HF_SA; | FAIRCHILD | FDS8878_G | Multiple |  | Purchase | SMT | 2 | PCS | Q35 Q36 |
| A | B55.01102.M003 | 84.04172.037 | FET MOS SI4172DY-T1-GE3 NC SO8 | R2_SA;HF_SA; | VISHAY | SI4172DY-T1-GE3 |  |  | Purchase |  |  |  |  |
| 3 | B55.01102.M003 | 84.2N702.031 | FET MOS 2N7002K-7 NC SOT-23 2KV 300MA | R2_SA;HF_SA; | DIODES | 2N7002K-7 | Single |  | Purchase | SMT | 8 | PCS | Q10 Q12 Q14 Q20 Q22 Q5 Q6 Q8 |
| 3 | B55.01102.M003 | 84.2N702.J31 | FET MOS 2N7002K NC SOT-23 ESD 2KV 300MA | R2_SA;HF_SA;G_SA; | PANJIT | 2N7002K | Single |  | Purchase | SMT | 2 | PCS | Q13 Q34 |
| 3 | B55.01102.M003 | B48.01121.0011 | PCB 16316-1 BRYCE CANYON SCC CARD 8L GCE | R2_SA;HF_SA; | GCE | B48.01121.0011 | Multiple |  | Purchase | SMT | 1 | PCS |  |
| A | B55.01102.M003 | B48.01146.0011 | PCB 16316-1 BRYCE CANYON SCC CARD 8L TRI | R2_SA;HF_SA; | TRIPOD | B48.01146.0011 |  |  | Purchase |  |  |  |  |
| 3 | B55.01102.M003 | BZA.01101.0050 | BRYCE CANYON EXP FW MODULE2 | R2; |  |  |  | M | Manufacture | SMT | 1 | PCS | FW |
| 4 | BZA.01101.0050 | 072.29128.0F09 | IC FEROM MX29GL128FDT2I-11G TSOP 56P | R2_SA;HF_SA; | MXIC | MX29GL128FDT2I-11G | Multiple |  | Purchase |  | 1 | PCS | U13 |
| A | BZA.01101.0050 | 72.29128.Z09 | IC FEROM S29GL128S10TFIV20 TSOP 56P | R2_SA;HF_SA; | SPANSION | S29GL128S10TFIV20 |  |  | Purchase |  |  |  |  |
| 4 | BZA.01101.0050 | B53.01101.00D1 | F/W BC EXPANDER 27.14.00.10_03 | R2; | TBD |  | Single |  | Manufacture |  | 1 | PCS |  |
| 3 | B55.01102.M003 | BZA.01101.0051 | BRYCE CANYON IOC F/W MODULE FOR SCC | R2; |  |  |  | M | Manufacture | SMT | 1 | PCS | FW |
| 4 | BZA.01101.0051 | 072.29128.0F09 | IC FEROM MX29GL128FDT2I-11G TSOP 56P | R2_SA;HF_SA; | MXIC | MX29GL128FDT2I-11G | Multiple |  | Purchase |  | 1 | PCS | U18 |
| A | BZA.01101.0051 | 72.29128.Z09 | IC FEROM S29GL128S10TFIV20 TSOP 56P | R2_SA;HF_SA; | SPANSION | S29GL128S10TFIV20 |  |  | Purchase |  |  |  |  |
| 4 | BZA.01101.0051 | B53.01101.0071 | F/W IOC OFFLINE 13_00_0B022701 | R2; | TBD |  | Single |  | Manufacture |  | 1 | PCS |  |
| 3 | B55.01102.M003 | BZA.01101.0053 | BRYCE CANYON IOC EEPROM MODULE FOR SCC | R2; |  |  |  | M | Manufacture | SMT | 1 | PCS | FW |
| 4 | BZA.01101.0053 | 72.24C64.I01 | IC EEPROM CAT24C64WI-GT3 SOIC 8P | R2_SA;HF_SA;G_SA; | ON | CAT24C64WI-GT3 | Multiple |  | Purchase |  | 1 | PCS | U15 |
| A | BZA.01101.0053 | 72.24C64.K01 | IC EEPROM M24C64-RMN6TP SOIC 8P | R2_SA;HF_SA; | STMICROELECTRONICS INC | M24C64-RMN6TP |  |  | Purchase |  |  |  |  |
| 4 | BZA.01101.0053 | B53.01101.0081 | F/W IOC EEPROM 3008_FORTN | R2; | TBD |  | Single |  | Manufacture |  | 1 | PCS |  |
| 2 | B55.01102.0003 | YAS0-00054-000$001 | SCREW TAPPING PAN M2 L5 BLUE ZN CR3+ | R2_SA;HF_SA; | WENHAO | TBD | Single |  | Purchase | DIP | 2 | PCS |  |
